# T6G (Grand Teton) — schematic netlist excerpt (pin names and nets, part order shuffled) for the footprints in the layout excerpt that follows; sources: Cadence DE-HDL packaged netlist, KiCad conversion of 04192023_DAF0TMB3IC0_F0TG_MB_C_brd_V02_OCP.brd

PC325_1  Q_CAP  0.1UF 25V 10% X7R  pkg 0402  page 215 : A = SW_P12V_AUX_PVDDCR_SOC_P1_FLT ; B = GND
C2045  Q_CAP  100PF 50V 5% EMPTY  pkg 0402  page 257 : A = P3V3_PDB_AUX_ADC_MAM ; B = GND

(kicad_pcb
	(version 20260206)
	(generator "pcbnew")
	(generator_version "10.0")
	(general
		(thickness 1.6)
		(legacy_teardrops no)
	)
	(paper "A4")
	(title_block
		(title "04192023_DAF0TMB3IC0_F0TG_MB_C_brd_V02_OCP.brd")
		(comment 1 "Grand Teton / footprints 1181-1182 of 8354")
	)
	(layers
		(0 "F.Cu" signal "TOP")
		(4 "In1.Cu" signal "GND")
		(6 "In2.Cu" signal "IN1")
		(8 "In3.Cu" signal "GND1")
		(10 "In4.Cu" signal "IN2")
		(12 "In5.Cu" signal "GND2")
		(14 "In6.Cu" signal "IN3")
		(16 "In7.Cu" signal "GND3")
		(18 "In8.Cu" signal "VCC")
		(20 "In9.Cu" signal "VCC1")
		(22 "In10.Cu" signal "GND4")
		(24 "In11.Cu" signal "IN4")
		(26 "In12.Cu" signal "GND5")
		(28 "In13.Cu" signal "IN5")
		(30 "In14.Cu" signal "GND6")
		(32 "In15.Cu" signal "IN6")
		(34 "In16.Cu" signal "GND7")
		(2 "B.Cu" signal "BOTTOM")
		(9 "F.Adhes" user "F.Adhesive")
		(11 "B.Adhes" user "B.Adhesive")
		(13 "F.Paste" user "Package Geometry/Pastemask Top")
		(15 "B.Paste" user "Package Geometry/Pastemask Bottom")
		(5 "F.SilkS" user "Ref Des/Silkscreen Top")
		(7 "B.SilkS" user "Ref Des/Silkscreen Bottom")
		(1 "F.Mask" user "Board Geometry/Soldermask Top")
		(3 "B.Mask" user "Board Geometry/Soldermask Bottom")
		(17 "Dwgs.User" user "User.Drawings")
		(19 "Cmts.User" user "User.Comments")
		(21 "Eco1.User" user "User.Eco1")
		(23 "Eco2.User" user "User.Eco2")
		(25 "Edge.Cuts" user "Board Geometry/Outline")
		(27 "Margin" user)
		(31 "F.CrtYd" user "Package Geometry/Place Bound Top")
		(29 "B.CrtYd" user "Package Geometry/Place Bound Bottom")
		(35 "F.Fab" user "Ref Des/Assembly Top")
		(33 "B.Fab" user "Ref Des/Assembly Bottom")
	)
	(footprint ""
		(layer "F.Cu")
		(at 111.076486 -171.812458 90)
		(property "Reference" "PC325_1"
			(at 0 0 90)
			(layer "F.SilkS")
			(hide yes)
			(effects
				(font
					(size 1.27 1.27)
				)
			)
		)
		(property "Value" ""
			(at 0 0 90)
			(layer "F.Fab")
			(effects
				(font
					(size 1.27 1.27)
				)
			)
		)
		(duplicate_pad_numbers_are_jumpers no)
		(fp_line
			(start 0.7874 -0.4064)
			(end 0.7874 0.4064)
			(stroke
				(width 0.1524)
				(type default)
			)
			(layer "F.SilkS")
		)
		(fp_line
			(start -0.7874 -0.4064)
			(end 0.7874 -0.4064)
			(stroke
				(width 0.1524)
				(type default)
			)
			(layer "F.SilkS")
		)
		(fp_line
			(start 0.7874 0.4064)
			(end -0.7874 0.4064)
			(stroke
				(width 0.1524)
				(type default)
			)
			(layer "F.SilkS")
		)
		(fp_line
			(start -0.7874 0.4064)
			(end -0.7874 -0.4064)
			(stroke
				(width 0.1524)
				(type default)
			)
			(layer "F.SilkS")
		)
		(fp_line
			(start -0.12065 -0.305054)
			(end -0.12065 -0.2794)
			(stroke
				(width 0.1)
				(type default)
			)
			(layer "F.Fab")
		)
		(fp_line
			(start -0.67945 -0.305054)
			(end -0.12065 -0.305054)
			(stroke
				(width 0.1)
				(type default)
			)
			(layer "F.Fab")
		)
		(fp_line
			(start 0.67945 -0.3048)
			(end 0.67945 0.3048)
			(stroke
				(width 0.1)
				(type default)
			)
			(layer "F.Fab")
		)
		(fp_line
			(start 0.12065 -0.3048)
			(end 0.67945 -0.3048)
			(stroke
				(width 0.1)
				(type default)
			)
			(layer "F.Fab")
		)
		(fp_line
			(start 0.12065 -0.2794)
			(end 0.12065 -0.3048)
			(stroke
				(width 0.1)
				(type default)
			)
			(layer "F.Fab")
		)
		(fp_line
			(start -0.12065 -0.2794)
			(end 0.12065 -0.2794)
			(stroke
				(width 0.1)
				(type default)
			)
			(layer "F.Fab")
		)
		(fp_line
			(start 0.120396 0.2794)
			(end -0.12065 0.2794)
			(stroke
				(width 0.1)
				(type default)
			)
			(layer "F.Fab")
		)
		(fp_line
			(start -0.12065 0.2794)
			(end -0.12065 0.3048)
			(stroke
				(width 0.1)
				(type default)
			)
			(layer "F.Fab")
		)
		(fp_line
			(start 0.67945 0.3048)
			(end 0.120396 0.3048)
			(stroke
				(width 0.1)
				(type default)
			)
			(layer "F.Fab")
		)
		(fp_line
			(start 0.120396 0.3048)
			(end 0.120396 0.2794)
			(stroke
				(width 0.1)
				(type default)
			)
			(layer "F.Fab")
		)
		(fp_line
			(start -0.12065 0.3048)
			(end -0.67945 0.3048)
			(stroke
				(width 0.1)
				(type default)
			)
			(layer "F.Fab")
		)
		(fp_line
			(start -0.67945 0.3048)
			(end -0.67945 -0.305054)
			(stroke
				(width 0.1)
				(type default)
			)
			(layer "F.Fab")
		)
		(pad "1" smd circle
			(at -0.40005 0 90)
			(size 0 0)
			(layers "F.Cu" "F.Mask" "F.Paste")
			(net "SW_P12V_AUX_PVDDCR_SOC_P1_FLT")
		)
		(pad "2" smd circle
			(at 0.40005 0 90)
			(size 0 0)
			(layers "F.Cu" "F.Mask" "F.Paste")
			(net "GND")
		)
	)
	(footprint ""
		(layer "F.Cu")
		(at 329.360022 -33.969706)
		(property "Reference" "C2045"
			(at 0 0 0)
			(layer "F.SilkS")
			(hide yes)
			(effects
				(font
					(size 1.27 1.27)
				)
			)
		)
		(property "Value" ""
			(at 0 0 0)
			(layer "F.Fab")
			(effects
				(font
					(size 1.27 1.27)
				)
			)
		)
		(duplicate_pad_numbers_are_jumpers no)
		(fp_line
			(start -0.7874 -0.4064)
			(end 0.7874 -0.4064)
			(stroke
				(width 0.1524)
				(type default)
			)
			(layer "F.SilkS")
		)
		(fp_line
			(start -0.7874 0.4064)
			(end -0.7874 -0.4064)
			(stroke
				(width 0.1524)
				(type default)
			)
			(layer "F.SilkS")
		)
		(fp_line
			(start 0.7874 -0.4064)
			(end 0.7874 0.4064)
			(stroke
				(width 0.1524)
				(type default)
			)
			(layer "F.SilkS")
		)
		(fp_line
			(start 0.7874 0.4064)
			(end -0.7874 0.4064)
			(stroke
				(width 0.1524)
				(type default)
			)
			(layer "F.SilkS")
		)
		(fp_line
			(start -0.67945 -0.305054)
			(end -0.12065 -0.305054)
			(stroke
				(width 0.1)
				(type default)
			)
			(layer "F.Fab")
		)
		(fp_line
			(start -0.67945 0.3048)
			(end -0.67945 -0.305054)
			(stroke
				(width 0.1)
				(type default)
			)
			(layer "F.Fab")
		)
		(fp_line
			(start -0.12065 -0.305054)
			(end -0.12065 -0.2794)
			(stroke
				(width 0.1)
				(type default)
			)
			(layer "F.Fab")
		)
		(fp_line
			(start -0.12065 -0.2794)
			(end 0.12065 -0.2794)
			(stroke
				(width 0.1)
				(type default)
			)
			(layer "F.Fab")
		)
		(fp_line
			(start -0.12065 0.2794)
			(end -0.12065 0.3048)
			(stroke
				(width 0.1)
				(type default)
			)
			(layer "F.Fab")
		)
		(fp_line
			(start -0.12065 0.3048)
			(end -0.67945 0.3048)
			(stroke
				(width 0.1)
				(type default)
			)
			(layer "F.Fab")
		)
		(fp_line
			(start 0.120396 0.2794)
			(end -0.12065 0.2794)
			(stroke
				(width 0.1)
				(type default)
			)
			(layer "F.Fab")
		)
		(fp_line
			(start 0.120396 0.3048)
			(end 0.120396 0.2794)
			(stroke
				(width 0.1)
				(type default)
			)
			(layer "F.Fab")
		)
		(fp_line
			(start 0.12065 -0.3048)
			(end 0.67945 -0.3048)
			(stroke
				(width 0.1)
				(type default)
			)
			(layer "F.Fab")
		)
		(fp_line
			(start 0.12065 -0.2794)
			(end 0.12065 -0.3048)
			(stroke
				(width 0.1)
				(type default)
			)
			(layer "F.Fab")
		)
		(fp_line
			(start 0.67945 -0.3048)
			(end 0.67945 0.3048)
			(stroke
				(width 0.1)
				(type default)
			)
			(layer "F.Fab")
		)
		(fp_line
			(start 0.67945 0.3048)
			(end 0.120396 0.3048)
			(stroke
				(width 0.1)
				(type default)
			)
			(layer "F.Fab")
		)
		(pad "1" smd circle
			(at -0.40005 0)
			(size 0 0)
			(layers "F.Cu" "F.Mask" "F.Paste")
			(net "P3V3_PDB_AUX_ADC_MAM")
		)
		(pad "2" smd circle
			(at 0.40005 0)
			(size 0 0)
			(layers "F.Cu" "F.Mask" "F.Paste")
			(net "GND")
		)
	)
)
